# S9S_MB_2U (Grand Teton) — schematic netlist excerpt (pin names and nets, part order shuffled) for the footprints in the layout excerpt that follows; sources: Cadence DE-HDL packaged netlist, KiCad conversion of 03242023_DA0F0TMBIJ0_F0T_Motherboard_J_brd_V01_OCP.brd

R2552  Q_RES  0 5% CHIP  pkg 0402LF  page 284 : A = PWRGD_PVCCFA_EHV_FIVRA_CPU1 ; B = PWRGD_PVCCFA_EHV_FIVRA_CPU1_R
R254  Q_RES  240 1% CHIP  pkg 0402LF  page 120 : A = PVNN_TERM_CPU0 ; B = FM_S3M_CPU0_LVC1_GPIO_3

(kicad_pcb
	(version 20260206)
	(generator "pcbnew")
	(generator_version "10.0")
	(general
		(thickness 1.6)
		(legacy_teardrops no)
	)
	(paper "A4")
	(title_block
		(title "03242023_DA0F0TMBIJ0_F0T_Motherboard_J_brd_V01_OCP.brd")
		(comment 1 "Grand Teton / footprints 5186-5187 of 6105")
	)
	(layers
		(0 "F.Cu" signal "TOP")
		(4 "In1.Cu" signal "GND")
		(6 "In2.Cu" signal "IN1")
		(8 "In3.Cu" signal "GND1")
		(10 "In4.Cu" signal "IN2")
		(12 "In5.Cu" signal "GND2")
		(14 "In6.Cu" signal "IN3")
		(16 "In7.Cu" signal "GND3")
		(18 "In8.Cu" signal "VCC")
		(20 "In9.Cu" signal "VCC1")
		(22 "In10.Cu" signal "GND4")
		(24 "In11.Cu" signal "IN4")
		(26 "In12.Cu" signal "GND5")
		(28 "In13.Cu" signal "IN5")
		(30 "In14.Cu" signal "GND6")
		(32 "In15.Cu" signal "IN6")
		(34 "In16.Cu" signal "GND7")
		(2 "B.Cu" signal "BOTTOM")
		(9 "F.Adhes" user "F.Adhesive")
		(11 "B.Adhes" user "B.Adhesive")
		(13 "F.Paste" user "Package Geometry/Pastemask Top")
		(15 "B.Paste" user "Package Geometry/Pastemask Bottom")
		(5 "F.SilkS" user "Ref Des/Silkscreen Top")
		(7 "B.SilkS" user "Ref Des/Silkscreen Bottom")
		(1 "F.Mask" user "Board Geometry/Soldermask Top")
		(3 "B.Mask" user "Board Geometry/Soldermask Bottom")
		(17 "Dwgs.User" user "User.Drawings")
		(19 "Cmts.User" user "User.Comments")
		(21 "Eco1.User" user "User.Eco1")
		(23 "Eco2.User" user "User.Eco2")
		(25 "Edge.Cuts" user "Board Geometry/Outline")
		(27 "Margin" user)
		(31 "F.CrtYd" user "Package Geometry/Place Bound Top")
		(29 "B.CrtYd" user "Package Geometry/Place Bound Bottom")
		(35 "F.Fab" user "Ref Des/Assembly Top")
		(33 "B.Fab" user "Ref Des/Assembly Bottom")
	)
	(footprint ""
		(layer "B.Cu")
		(at 281.100784 -193.669666 -90)
		(property "Reference" "R254"
			(at 0 0 90)
			(layer "B.SilkS")
			(hide yes)
			(effects
				(font
					(size 1.27 1.27)
				)
				(justify mirror)
			)
		)
		(property "Value" ""
			(at 0 0 90)
			(layer "B.Fab")
			(effects
				(font
					(size 1.27 1.27)
				)
				(justify mirror)
			)
		)
		(duplicate_pad_numbers_are_jumpers no)
		(fp_line
			(start -0.7874 0.4064)
			(end 0.7874 0.4064)
			(stroke
				(width 0.1524)
				(type default)
			)
			(layer "B.SilkS")
		)
		(fp_line
			(start 0.7874 0.4064)
			(end 0.7874 -0.4064)
			(stroke
				(width 0.1524)
				(type default)
			)
			(layer "B.SilkS")
		)
		(fp_line
			(start -0.7874 -0.4064)
			(end -0.7874 0.4064)
			(stroke
				(width 0.1524)
				(type default)
			)
			(layer "B.SilkS")
		)
		(fp_line
			(start 0.7874 -0.4064)
			(end -0.7874 -0.4064)
			(stroke
				(width 0.1524)
				(type default)
			)
			(layer "B.SilkS")
		)
		(fp_line
			(start -0.67945 0.3048)
			(end -0.120396 0.3048)
			(stroke
				(width 0.1)
				(type default)
			)
			(layer "B.Fab")
		)
		(fp_line
			(start -0.120396 0.3048)
			(end -0.120396 0.2794)
			(stroke
				(width 0.1)
				(type default)
			)
			(layer "B.Fab")
		)
		(fp_line
			(start 0.12065 0.3048)
			(end 0.67945 0.3048)
			(stroke
				(width 0.1)
				(type default)
			)
			(layer "B.Fab")
		)
		(fp_line
			(start 0.67945 0.3048)
			(end 0.67945 -0.305054)
			(stroke
				(width 0.1)
				(type default)
			)
			(layer "B.Fab")
		)
		(fp_line
			(start -0.120396 0.2794)
			(end 0.12065 0.2794)
			(stroke
				(width 0.1)
				(type default)
			)
			(layer "B.Fab")
		)
		(fp_line
			(start 0.12065 0.2794)
			(end 0.12065 0.3048)
			(stroke
				(width 0.1)
				(type default)
			)
			(layer "B.Fab")
		)
		(fp_line
			(start -0.12065 -0.2794)
			(end -0.12065 -0.3048)
			(stroke
				(width 0.1)
				(type default)
			)
			(layer "B.Fab")
		)
		(fp_line
			(start 0.12065 -0.2794)
			(end -0.12065 -0.2794)
			(stroke
				(width 0.1)
				(type default)
			)
			(layer "B.Fab")
		)
		(fp_line
			(start -0.67945 -0.3048)
			(end -0.67945 0.3048)
			(stroke
				(width 0.1)
				(type default)
			)
			(layer "B.Fab")
		)
		(fp_line
			(start -0.12065 -0.3048)
			(end -0.67945 -0.3048)
			(stroke
				(width 0.1)
				(type default)
			)
			(layer "B.Fab")
		)
		(fp_line
			(start 0.12065 -0.305054)
			(end 0.12065 -0.2794)
			(stroke
				(width 0.1)
				(type default)
			)
			(layer "B.Fab")
		)
		(fp_line
			(start 0.67945 -0.305054)
			(end 0.12065 -0.305054)
			(stroke
				(width 0.1)
				(type default)
			)
			(layer "B.Fab")
		)
		(pad "1" smd circle
			(at 0.40005 0 90)
			(size 0 0)
			(layers "B.Cu" "B.Mask" "B.Paste")
			(net "PVNN_TERM_CPU0")
		)
		(pad "2" smd circle
			(at -0.40005 0 90)
			(size 0 0)
			(layers "B.Cu" "B.Mask" "B.Paste")
			(net "FM_S3M_CPU0_LVC1_GPIO_3")
		)
	)
	(footprint ""
		(layer "B.Cu")
		(at 100.306886 -358.899714 180)
		(property "Reference" "R2552"
			(at 0 0 0)
			(layer "B.SilkS")
			(hide yes)
			(effects
				(font
					(size 1.27 1.27)
				)
				(justify mirror)
			)
		)
		(property "Value" ""
			(at 0 0 0)
			(layer "B.Fab")
			(effects
				(font
					(size 1.27 1.27)
				)
				(justify mirror)
			)
		)
		(duplicate_pad_numbers_are_jumpers no)
		(fp_line
			(start 0.7874 0.4064)
			(end 0.7874 -0.4064)
			(stroke
				(width 0.1524)
				(type default)
			)
			(layer "B.SilkS")
		)
		(fp_line
			(start 0.7874 -0.4064)
			(end -0.7874 -0.4064)
			(stroke
				(width 0.1524)
				(type default)
			)
			(layer "B.SilkS")
		)
		(fp_line
			(start -0.7874 0.4064)
			(end 0.7874 0.4064)
			(stroke
				(width 0.1524)
				(type default)
			)
			(layer "B.SilkS")
		)
		(fp_line
			(start -0.7874 -0.4064)
			(end -0.7874 0.4064)
			(stroke
				(width 0.1524)
				(type default)
			)
			(layer "B.SilkS")
		)
		(fp_line
			(start 0.67945 0.3048)
			(end 0.67945 -0.305054)
			(stroke
				(width 0.1)
				(type default)
			)
			(layer "B.Fab")
		)
		(fp_line
			(start 0.67945 -0.305054)
			(end 0.12065 -0.305054)
			(stroke
				(width 0.1)
				(type default)
			)
			(layer "B.Fab")
		)
		(fp_line
			(start 0.12065 0.3048)
			(end 0.67945 0.3048)
			(stroke
				(width 0.1)
				(type default)
			)
			(layer "B.Fab")
		)
		(fp_line
			(start 0.12065 0.2794)
			(end 0.12065 0.3048)
			(stroke
				(width 0.1)
				(type default)
			)
			(layer "B.Fab")
		)
		(fp_line
			(start 0.12065 -0.2794)
			(end -0.12065 -0.2794)
			(stroke
				(width 0.1)
				(type default)
			)
			(layer "B.Fab")
		)
		(fp_line
			(start 0.12065 -0.305054)
			(end 0.12065 -0.2794)
			(stroke
				(width 0.1)
				(type default)
			)
			(layer "B.Fab")
		)
		(fp_line
			(start -0.120396 0.3048)
			(end -0.120396 0.2794)
			(stroke
				(width 0.1)
				(type default)
			)
			(layer "B.Fab")
		)
		(fp_line
			(start -0.120396 0.2794)
			(end 0.12065 0.2794)
			(stroke
				(width 0.1)
				(type default)
			)
			(layer "B.Fab")
		)
		(fp_line
			(start -0.12065 -0.2794)
			(end -0.12065 -0.3048)
			(stroke
				(width 0.1)
				(type default)
			)
			(layer "B.Fab")
		)
		(fp_line
			(start -0.12065 -0.3048)
			(end -0.67945 -0.3048)
			(stroke
				(width 0.1)
				(type default)
			)
			(layer "B.Fab")
		)
		(fp_line
			(start -0.67945 0.3048)
			(end -0.120396 0.3048)
			(stroke
				(width 0.1)
				(type default)
			)
			(layer "B.Fab")
		)
		(fp_line
			(start -0.67945 -0.3048)
			(end -0.67945 0.3048)
			(stroke
				(width 0.1)
				(type default)
			)
			(layer "B.Fab")
		)
		(pad "1" smd circle
			(at 0.40005 0)
			(size 0 0)
			(layers "B.Cu" "B.Mask" "B.Paste")
			(net "PWRGD_PVCCFA_EHV_FIVRA_CPU1")
		)
		(pad "2" smd circle
			(at -0.40005 0)
			(size 0 0)
			(layers "B.Cu" "B.Mask" "B.Paste")
			(net "PWRGD_PVCCFA_EHV_FIVRA_CPU1_R")
		)
	)
)
